(kicad_pcb
	(version 20260206)
	(generator "pcbnew")
	(generator_version "10.0")
	(general
		(thickness 1.6)
		(legacy_teardrops no)
	)
	(paper "A4")
	(title_block
		(title "04192023_DAF0TMB3IC0_F0TG_MB_C_brd_V02_OCP.brd")
		(comment 1 "Grand Teton / footprints 6318-6324 of 8354")
	)
	(layers
		(0 "F.Cu" signal "TOP")
		(4 "In1.Cu" signal "GND")
		(6 "In2.Cu" signal "IN1")
		(8 "In3.Cu" signal "GND1")
		(10 "In4.Cu" signal "IN2")
		(12 "In5.Cu" signal "GND2")
		(14 "In6.Cu" signal "IN3")
		(16 "In7.Cu" signal "GND3")
		(18 "In8.Cu" signal "VCC")
		(20 "In9.Cu" signal "VCC1")
		(22 "In10.Cu" signal "GND4")
		(24 "In11.Cu" signal "IN4")
		(26 "In12.Cu" signal "GND5")
		(28 "In13.Cu" signal "IN5")
		(30 "In14.Cu" signal "GND6")
		(32 "In15.Cu" signal "IN6")
		(34 "In16.Cu" signal "GND7")
		(2 "B.Cu" signal "BOTTOM")
		(9 "F.Adhes" user "F.Adhesive")
		(11 "B.Adhes" user "B.Adhesive")
		(13 "F.Paste" user "Package Geometry/Pastemask Top")
		(15 "B.Paste" user "Package Geometry/Pastemask Bottom")
		(5 "F.SilkS" user "Ref Des/Silkscreen Top")
		(7 "B.SilkS" user "Ref Des/Silkscreen Bottom")
		(1 "F.Mask" user "Board Geometry/Soldermask Top")
		(3 "B.Mask" user "Board Geometry/Soldermask Bottom")
		(17 "Dwgs.User" user "User.Drawings")
		(19 "Cmts.User" user "User.Comments")
		(21 "Eco1.User" user "User.Eco1")
		(23 "Eco2.User" user "User.Eco2")
		(25 "Edge.Cuts" user "Board Geometry/Outline")
		(27 "Margin" user)
		(31 "F.CrtYd" user "Package Geometry/Place Bound Top")
		(29 "B.CrtYd" user "Package Geometry/Place Bound Bottom")
		(35 "F.Fab" user "Ref Des/Assembly Top")
		(33 "B.Fab" user "Ref Des/Assembly Bottom")
	)
	(footprint ""
		(layer "B.Cu")
		(at 51.766978 -428.06493 90)
		(property "Reference" "C1978"
			(at 0 0 90)
			(layer "B.SilkS")
			(hide yes)
			(effects
				(font
					(size 1.27 1.27)
				)
				(justify mirror)
			)
		)
		(property "Value" ""
			(at 0 0 90)
			(layer "B.Fab")
			(effects
				(font
					(size 1.27 1.27)
				)
				(justify mirror)
			)
		)
		(duplicate_pad_numbers_are_jumpers no)
		(fp_line
			(start 0.7874 -0.4064)
			(end -0.7874 -0.4064)
			(stroke
				(width 0.1524)
				(type default)
			)
			(layer "B.SilkS")
		)
		(fp_line
			(start -0.7874 -0.4064)
			(end -0.7874 0.4064)
			(stroke
				(width 0.1524)
				(type default)
			)
			(layer "B.SilkS")
		)
		(fp_line
			(start 0.7874 0.4064)
			(end 0.7874 -0.4064)
			(stroke
				(width 0.1524)
				(type default)
			)
			(layer "B.SilkS")
		)
		(fp_line
			(start -0.7874 0.4064)
			(end 0.7874 0.4064)
			(stroke
				(width 0.1524)
				(type default)
			)
			(layer "B.SilkS")
		)
		(fp_line
			(start 0.67945 -0.305054)
			(end 0.12065 -0.305054)
			(stroke
				(width 0.1)
				(type default)
			)
			(layer "B.Fab")
		)
		(fp_line
			(start 0.12065 -0.305054)
			(end 0.12065 -0.2794)
			(stroke
				(width 0.1)
				(type default)
			)
			(layer "B.Fab")
		)
		(fp_line
			(start -0.12065 -0.3048)
			(end -0.67945 -0.3048)
			(stroke
				(width 0.1)
				(type default)
			)
			(layer "B.Fab")
		)
		(fp_line
			(start -0.67945 -0.3048)
			(end -0.67945 0.3048)
			(stroke
				(width 0.1)
				(type default)
			)
			(layer "B.Fab")
		)
		(fp_line
			(start 0.12065 -0.2794)
			(end -0.12065 -0.2794)
			(stroke
				(width 0.1)
				(type default)
			)
			(layer "B.Fab")
		)
		(fp_line
			(start -0.12065 -0.2794)
			(end -0.12065 -0.3048)
			(stroke
				(width 0.1)
				(type default)
			)
			(layer "B.Fab")
		)
		(fp_line
			(start 0.12065 0.2794)
			(end 0.12065 0.3048)
			(stroke
				(width 0.1)
				(type default)
			)
			(layer "B.Fab")
		)
		(fp_line
			(start -0.120396 0.2794)
			(end 0.12065 0.2794)
			(stroke
				(width 0.1)
				(type default)
			)
			(layer "B.Fab")
		)
		(fp_line
			(start 0.67945 0.3048)
			(end 0.67945 -0.305054)
			(stroke
				(width 0.1)
				(type default)
			)
			(layer "B.Fab")
		)
		(fp_line
			(start 0.12065 0.3048)
			(end 0.67945 0.3048)
			(stroke
				(width 0.1)
				(type default)
			)
			(layer "B.Fab")
		)
		(fp_line
			(start -0.120396 0.3048)
			(end -0.120396 0.2794)
			(stroke
				(width 0.1)
				(type default)
			)
			(layer "B.Fab")
		)
		(fp_line
			(start -0.67945 0.3048)
			(end -0.120396 0.3048)
			(stroke
				(width 0.1)
				(type default)
			)
			(layer "B.Fab")
		)
		(pad "1" smd circle
			(at 0.40005 0 270)
			(size 0 0)
			(layers "B.Cu" "B.Mask" "B.Paste")
			(net "GPU_PRSNT_N_ISO")
		)
		(pad "2" smd circle
			(at -0.40005 0 270)
			(size 0 0)
			(layers "B.Cu" "B.Mask" "B.Paste")
			(net "GND")
		)
	)
	(footprint ""
		(layer "B.Cu")
		(at 406.698958 -323.846952)
		(property "Reference" "R458"
			(at 0 0 0)
			(layer "B.SilkS")
			(hide yes)
			(effects
				(font
					(size 1.27 1.27)
				)
				(justify mirror)
			)
		)
		(property "Value" ""
			(at 0 0 0)
			(layer "B.Fab")
			(effects
				(font
					(size 1.27 1.27)
				)
				(justify mirror)
			)
		)
		(duplicate_pad_numbers_are_jumpers no)
		(fp_line
			(start -0.7874 -0.4064)
			(end -0.7874 0.4064)
			(stroke
				(width 0.1524)
				(type default)
			)
			(layer "B.SilkS")
		)
		(fp_line
			(start -0.7874 0.4064)
			(end 0.7874 0.4064)
			(stroke
				(width 0.1524)
				(type default)
			)
			(layer "B.SilkS")
		)
		(fp_line
			(start 0.7874 -0.4064)
			(end -0.7874 -0.4064)
			(stroke
				(width 0.1524)
				(type default)
			)
			(layer "B.SilkS")
		)
		(fp_line
			(start 0.7874 0.4064)
			(end 0.7874 -0.4064)
			(stroke
				(width 0.1524)
				(type default)
			)
			(layer "B.SilkS")
		)
		(fp_line
			(start -0.67945 -0.3048)
			(end -0.67945 0.3048)
			(stroke
				(width 0.1)
				(type default)
			)
			(layer "B.Fab")
		)
		(fp_line
			(start -0.67945 0.3048)
			(end -0.120396 0.3048)
			(stroke
				(width 0.1)
				(type default)
			)
			(layer "B.Fab")
		)
		(fp_line
			(start -0.12065 -0.3048)
			(end -0.67945 -0.3048)
			(stroke
				(width 0.1)
				(type default)
			)
			(layer "B.Fab")
		)
		(fp_line
			(start -0.12065 -0.2794)
			(end -0.12065 -0.3048)
			(stroke
				(width 0.1)
				(type default)
			)
			(layer "B.Fab")
		)
		(fp_line
			(start -0.120396 0.2794)
			(end 0.12065 0.2794)
			(stroke
				(width 0.1)
				(type default)
			)
			(layer "B.Fab")
		)
		(fp_line
			(start -0.120396 0.3048)
			(end -0.120396 0.2794)
			(stroke
				(width 0.1)
				(type default)
			)
			(layer "B.Fab")
		)
		(fp_line
			(start 0.12065 -0.305054)
			(end 0.12065 -0.2794)
			(stroke
				(width 0.1)
				(type default)
			)
			(layer "B.Fab")
		)
		(fp_line
			(start 0.12065 -0.2794)
			(end -0.12065 -0.2794)
			(stroke
				(width 0.1)
				(type default)
			)
			(layer "B.Fab")
		)
		(fp_line
			(start 0.12065 0.2794)
			(end 0.12065 0.3048)
			(stroke
				(width 0.1)
				(type default)
			)
			(layer "B.Fab")
		)
		(fp_line
			(start 0.12065 0.3048)
			(end 0.67945 0.3048)
			(stroke
				(width 0.1)
				(type default)
			)
			(layer "B.Fab")
		)
		(fp_line
			(start 0.67945 -0.305054)
			(end 0.12065 -0.305054)
			(stroke
				(width 0.1)
				(type default)
			)
			(layer "B.Fab")
		)
		(fp_line
			(start 0.67945 0.3048)
			(end 0.67945 -0.305054)
			(stroke
				(width 0.1)
				(type default)
			)
			(layer "B.Fab")
		)
		(pad "1" smd circle
			(at 0.40005 0 180)
			(size 0 0)
			(layers "B.Cu" "B.Mask" "B.Paste")
			(net "PVDD18_S5_P0")
		)
		(pad "2" smd circle
			(at -0.40005 0 180)
			(size 0 0)
			(layers "B.Cu" "B.Mask" "B.Paste")
			(net "ESPI_CPU0_ALERT_P0_N")
		)
	)
	(footprint ""
		(layer "B.Cu")
		(at 244.729 -218.186 -90)
		(property "Reference" "R200"
			(at 0 0 90)
			(layer "B.SilkS")
			(hide yes)
			(effects
				(font
					(size 1.27 1.27)
				)
				(justify mirror)
			)
		)
		(property "Value" ""
			(at 0 0 90)
			(layer "B.Fab")
			(effects
				(font
					(size 1.27 1.27)
				)
				(justify mirror)
			)
		)
		(duplicate_pad_numbers_are_jumpers no)
		(fp_line
			(start -0.7874 0.4064)
			(end 0.7874 0.4064)
			(stroke
				(width 0.1524)
				(type default)
			)
			(layer "B.SilkS")
		)
		(fp_line
			(start 0.7874 0.4064)
			(end 0.7874 -0.4064)
			(stroke
				(width 0.1524)
				(type default)
			)
			(layer "B.SilkS")
		)
		(fp_line
			(start -0.7874 -0.4064)
			(end -0.7874 0.4064)
			(stroke
				(width 0.1524)
				(type default)
			)
			(layer "B.SilkS")
		)
		(fp_line
			(start 0.7874 -0.4064)
			(end -0.7874 -0.4064)
			(stroke
				(width 0.1524)
				(type default)
			)
			(layer "B.SilkS")
		)
		(fp_line
			(start -0.67945 0.3048)
			(end -0.120396 0.3048)
			(stroke
				(width 0.1)
				(type default)
			)
			(layer "B.Fab")
		)
		(fp_line
			(start -0.120396 0.3048)
			(end -0.120396 0.2794)
			(stroke
				(width 0.1)
				(type default)
			)
			(layer "B.Fab")
		)
		(fp_line
			(start 0.12065 0.3048)
			(end 0.67945 0.3048)
			(stroke
				(width 0.1)
				(type default)
			)
			(layer "B.Fab")
		)
		(fp_line
			(start 0.67945 0.3048)
			(end 0.67945 -0.305054)
			(stroke
				(width 0.1)
				(type default)
			)
			(layer "B.Fab")
		)
		(fp_line
			(start -0.120396 0.2794)
			(end 0.12065 0.2794)
			(stroke
				(width 0.1)
				(type default)
			)
			(layer "B.Fab")
		)
		(fp_line
			(start 0.12065 0.2794)
			(end 0.12065 0.3048)
			(stroke
				(width 0.1)
				(type default)
			)
			(layer "B.Fab")
		)
		(fp_line
			(start -0.12065 -0.2794)
			(end -0.12065 -0.3048)
			(stroke
				(width 0.1)
				(type default)
			)
			(layer "B.Fab")
		)
		(fp_line
			(start 0.12065 -0.2794)
			(end -0.12065 -0.2794)
			(stroke
				(width 0.1)
				(type default)
			)
			(layer "B.Fab")
		)
		(fp_line
			(start -0.67945 -0.3048)
			(end -0.67945 0.3048)
			(stroke
				(width 0.1)
				(type default)
			)
			(layer "B.Fab")
		)
		(fp_line
			(start -0.12065 -0.3048)
			(end -0.67945 -0.3048)
			(stroke
				(width 0.1)
				(type default)
			)
			(layer "B.Fab")
		)
		(fp_line
			(start 0.12065 -0.305054)
			(end 0.12065 -0.2794)
			(stroke
				(width 0.1)
				(type default)
			)
			(layer "B.Fab")
		)
		(fp_line
			(start 0.67945 -0.305054)
			(end 0.12065 -0.305054)
			(stroke
				(width 0.1)
				(type default)
			)
			(layer "B.Fab")
		)
		(pad "1" smd circle
			(at 0.40005 0 90)
			(size 0 0)
			(layers "B.Cu" "B.Mask" "B.Paste")
			(net "P3V3_AUX")
		)
		(pad "2" smd circle
			(at -0.40005 0 90)
			(size 0 0)
			(layers "B.Cu" "B.Mask" "B.Paste")
			(net "PU_U96_EN")
		)
	)
	(footprint ""
		(layer "B.Cu")
		(at 357.443786 -395.466062 -90)
		(property "Reference" "C588"
			(at 0 0 90)
			(layer "B.SilkS")
			(hide yes)
			(effects
				(font
					(size 1.27 1.27)
				)
				(justify mirror)
			)
		)
		(property "Value" ""
			(at 0 0 90)
			(layer "B.Fab")
			(effects
				(font
					(size 1.27 1.27)
				)
				(justify mirror)
			)
		)
		(duplicate_pad_numbers_are_jumpers no)
		(fp_line
			(start -1.524 0.762)
			(end 1.524 0.762)
			(stroke
				(width 0.1524)
				(type default)
			)
			(layer "B.SilkS")
		)
		(fp_line
			(start 1.524 0.762)
			(end 1.524 -0.762)
			(stroke
				(width 0.1524)
				(type default)
			)
			(layer "B.SilkS")
		)
		(fp_line
			(start -1.524 -0.762)
			(end -1.524 0.762)
			(stroke
				(width 0.1524)
				(type default)
			)
			(layer "B.SilkS")
		)
		(fp_line
			(start 1.524 -0.762)
			(end -1.524 -0.762)
			(stroke
				(width 0.1524)
				(type default)
			)
			(layer "B.SilkS")
		)
		(fp_line
			(start -1.1049 0.724916)
			(end -1.1049 -0.724916)
			(stroke
				(width 0.1)
				(type default)
			)
			(layer "B.Fab")
		)
		(fp_line
			(start 1.1049 0.724916)
			(end -1.1049 0.724916)
			(stroke
				(width 0.1)
				(type default)
			)
			(layer "B.Fab")
		)
		(fp_line
			(start -1.1049 -0.724916)
			(end 1.1049 -0.724916)
			(stroke
				(width 0.1)
				(type default)
			)
			(layer "B.Fab")
		)
		(fp_line
			(start 1.1049 -0.724916)
			(end 1.1049 0.724916)
			(stroke
				(width 0.1)
				(type default)
			)
			(layer "B.Fab")
		)
		(pad "1" smd rect
			(at 0.889 0 270)
			(size 1.016 1.27)
			(layers "B.Cu" "B.Mask" "B.Paste")
			(net "P1V8_CPU0_RT1_1A")
		)
		(pad "2" smd rect
			(at -0.889 0 270)
			(size 1.016 1.27)
			(layers "B.Cu" "B.Mask" "B.Paste")
			(net "GND")
		)
	)
	(footprint ""
		(layer "B.Cu")
		(at 11.853418 -412.85287 180)
		(property "Reference" "PR885"
			(at 0 0 0)
			(layer "B.SilkS")
			(hide yes)
			(effects
				(font
					(size 1.27 1.27)
				)
				(justify mirror)
			)
		)
		(property "Value" ""
			(at 0 0 0)
			(layer "B.Fab")
			(effects
				(font
					(size 1.27 1.27)
				)
				(justify mirror)
			)
		)
		(duplicate_pad_numbers_are_jumpers no)
		(fp_line
			(start 0.7874 0.4064)
			(end 0.7874 -0.4064)
			(stroke
				(width 0.1524)
				(type default)
			)
			(layer "B.SilkS")
		)
		(fp_line
			(start 0.7874 -0.4064)
			(end -0.7874 -0.4064)
			(stroke
				(width 0.1524)
				(type default)
			)
			(layer "B.SilkS")
		)
		(fp_line
			(start -0.7874 0.4064)
			(end 0.7874 0.4064)
			(stroke
				(width 0.1524)
				(type default)
			)
			(layer "B.SilkS")
		)
		(fp_line
			(start -0.7874 -0.4064)
			(end -0.7874 0.4064)
			(stroke
				(width 0.1524)
				(type default)
			)
			(layer "B.SilkS")
		)
		(fp_line
			(start 0.67945 0.3048)
			(end 0.67945 -0.305054)
			(stroke
				(width 0.1)
				(type default)
			)
			(layer "B.Fab")
		)
		(fp_line
			(start 0.67945 -0.305054)
			(end 0.12065 -0.305054)
			(stroke
				(width 0.1)
				(type default)
			)
			(layer "B.Fab")
		)
		(fp_line
			(start 0.12065 0.3048)
			(end 0.67945 0.3048)
			(stroke
				(width 0.1)
				(type default)
			)
			(layer "B.Fab")
		)
		(fp_line
			(start 0.12065 0.2794)
			(end 0.12065 0.3048)
			(stroke
				(width 0.1)
				(type default)
			)
			(layer "B.Fab")
		)
		(fp_line
			(start 0.12065 -0.2794)
			(end -0.12065 -0.2794)
			(stroke
				(width 0.1)
				(type default)
			)
			(layer "B.Fab")
		)
		(fp_line
			(start 0.12065 -0.305054)
			(end 0.12065 -0.2794)
			(stroke
				(width 0.1)
				(type default)
			)
			(layer "B.Fab")
		)
		(fp_line
			(start -0.120396 0.3048)
			(end -0.120396 0.2794)
			(stroke
				(width 0.1)
				(type default)
			)
			(layer "B.Fab")
		)
		(fp_line
			(start -0.120396 0.2794)
			(end 0.12065 0.2794)
			(stroke
				(width 0.1)
				(type default)
			)
			(layer "B.Fab")
		)
		(fp_line
			(start -0.12065 -0.2794)
			(end -0.12065 -0.3048)
			(stroke
				(width 0.1)
				(type default)
			)
			(layer "B.Fab")
		)
		(fp_line
			(start -0.12065 -0.3048)
			(end -0.67945 -0.3048)
			(stroke
				(width 0.1)
				(type default)
			)
			(layer "B.Fab")
		)
		(fp_line
			(start -0.67945 0.3048)
			(end -0.120396 0.3048)
			(stroke
				(width 0.1)
				(type default)
			)
			(layer "B.Fab")
		)
		(fp_line
			(start -0.67945 -0.3048)
			(end -0.67945 0.3048)
			(stroke
				(width 0.1)
				(type default)
			)
			(layer "B.Fab")
		)
		(pad "1" smd circle
			(at 0.40005 0)
			(size 0 0)
			(layers "B.Cu" "B.Mask" "B.Paste")
			(net "P5V_AUX")
		)
		(pad "2" smd circle
			(at -0.40005 0)
			(size 0 0)
			(layers "B.Cu" "B.Mask" "B.Paste")
			(net "P0V9_RETIMER_CPU1_VMON")
		)
	)
	(footprint ""
		(layer "B.Cu")
		(at 106.978958 -340.007194 90)
		(property "Reference" "PC145_6"
			(at 0 0 90)
			(layer "B.SilkS")
			(hide yes)
			(effects
				(font
					(size 1.27 1.27)
				)
				(justify mirror)
			)
		)
		(property "Value" ""
			(at 0 0 90)
			(layer "B.Fab")
			(effects
				(font
					(size 1.27 1.27)
				)
				(justify mirror)
			)
		)
		(duplicate_pad_numbers_are_jumpers no)
		(fp_line
			(start 1.524 -0.762)
			(end -1.524 -0.762)
			(stroke
				(width 0.1524)
				(type default)
			)
			(layer "B.SilkS")
		)
		(fp_line
			(start -1.524 -0.762)
			(end -1.524 0.762)
			(stroke
				(width 0.1524)
				(type default)
			)
			(layer "B.SilkS")
		)
		(fp_line
			(start 1.524 0.762)
			(end 1.524 -0.762)
			(stroke
				(width 0.1524)
				(type default)
			)
			(layer "B.SilkS")
		)
		(fp_line
			(start -1.524 0.762)
			(end 1.524 0.762)
			(stroke
				(width 0.1524)
				(type default)
			)
			(layer "B.SilkS")
		)
		(fp_line
			(start 1.1049 -0.724916)
			(end 1.1049 0.724916)
			(stroke
				(width 0.1)
				(type default)
			)
			(layer "B.Fab")
		)
		(fp_line
			(start -1.1049 -0.724916)
			(end 1.1049 -0.724916)
			(stroke
				(width 0.1)
				(type default)
			)
			(layer "B.Fab")
		)
		(fp_line
			(start 1.1049 0.724916)
			(end -1.1049 0.724916)
			(stroke
				(width 0.1)
				(type default)
			)
			(layer "B.Fab")
		)
		(fp_line
			(start -1.1049 0.724916)
			(end -1.1049 -0.724916)
			(stroke
				(width 0.1)
				(type default)
			)
			(layer "B.Fab")
		)
		(pad "1" smd rect
			(at 0.889 0 90)
			(size 1.016 1.27)
			(layers "B.Cu" "B.Mask" "B.Paste")
			(net "SW_P12V_AUX_PVDDCR_CPU1_P1_FLT")
		)
		(pad "2" smd rect
			(at -0.889 0 90)
			(size 1.016 1.27)
			(layers "B.Cu" "B.Mask" "B.Paste")
			(net "GND")
		)
	)
	(footprint ""
		(layer "B.Cu")
		(at 427.456092 -192.660016 180)
		(property "Reference" "C162"
			(at 0 0 0)
			(layer "B.SilkS")
			(hide yes)
			(effects
				(font
					(size 1.27 1.27)
				)
				(justify mirror)
			)
		)
		(property "Value" ""
			(at 0 0 0)
			(layer "B.Fab")
			(effects
				(font
					(size 1.27 1.27)
				)
				(justify mirror)
			)
		)
		(duplicate_pad_numbers_are_jumpers no)
		(fp_line
			(start 1.524 0.762)
			(end 1.524 -0.762)
			(stroke
				(width 0.1524)
				(type default)
			)
			(layer "B.SilkS")
		)
		(fp_line
			(start 1.524 -0.762)
			(end -1.524 -0.762)
			(stroke
				(width 0.1524)
				(type default)
			)
			(layer "B.SilkS")
		)
		(fp_line
			(start -1.524 0.762)
			(end 1.524 0.762)
			(stroke
				(width 0.1524)
				(type default)
			)
			(layer "B.SilkS")
		)
		(fp_line
			(start -1.524 -0.762)
			(end -1.524 0.762)
			(stroke
				(width 0.1524)
				(type default)
			)
			(layer "B.SilkS")
		)
		(fp_line
			(start 1.1049 0.724916)
			(end -1.1049 0.724916)
			(stroke
				(width 0.1)
				(type default)
			)
			(layer "B.Fab")
		)
		(fp_line
			(start 1.1049 -0.724916)
			(end 1.1049 0.724916)
			(stroke
				(width 0.1)
				(type default)
			)
			(layer "B.Fab")
		)
		(fp_line
			(start -1.1049 0.724916)
			(end -1.1049 -0.724916)
			(stroke
				(width 0.1)
				(type default)
			)
			(layer "B.Fab")
		)
		(fp_line
			(start -1.1049 -0.724916)
			(end 1.1049 -0.724916)
			(stroke
				(width 0.1)
				(type default)
			)
			(layer "B.Fab")
		)
		(pad "1" smd rect
			(at 0.889 0 180)
			(size 1.016 1.27)
			(layers "B.Cu" "B.Mask" "B.Paste")
			(net "P12V_MEM_CPU0")
		)
		(pad "2" smd rect
			(at -0.889 0 180)
			(size 1.016 1.27)
			(layers "B.Cu" "B.Mask" "B.Paste")
			(net "GND")
		)
	)
)
